# T6G (Grand Teton) — schematic netlist excerpt (pin names and nets, part order shuffled) for the footprints in the layout excerpt that follows; sources: Cadence DE-HDL packaged netlist, KiCad conversion of 04192023_DAF0TMB3IC0_F0TG_MB_C_brd_V02_OCP.brd

PR330  Q_RES  5.6 1% CHIP  pkg 0402LF  page 225 : A = SW_PVDD11_S3_P1_BOOT1 ; B = SW_PVDD11_S3_P1_BOOT1_RC
PC6630  Q_CAPP  390UF 2.5V 20% ALUM  pkg SMLF  page 365 : A = P0V9_CPU1_RT_2D ; B = GND

(kicad_pcb
	(version 20260206)
	(generator "pcbnew")
	(generator_version "10.0")
	(general
		(thickness 1.6)
		(legacy_teardrops no)
	)
	(paper "A4")
	(title_block
		(title "04192023_DAF0TMB3IC0_F0TG_MB_C_brd_V02_OCP.brd")
		(comment 1 "Grand Teton / footprints 3674-3675 of 8354")
	)
	(layers
		(0 "F.Cu" signal "TOP")
		(4 "In1.Cu" signal "GND")
		(6 "In2.Cu" signal "IN1")
		(8 "In3.Cu" signal "GND1")
		(10 "In4.Cu" signal "IN2")
		(12 "In5.Cu" signal "GND2")
		(14 "In6.Cu" signal "IN3")
		(16 "In7.Cu" signal "GND3")
		(18 "In8.Cu" signal "VCC")
		(20 "In9.Cu" signal "VCC1")
		(22 "In10.Cu" signal "GND4")
		(24 "In11.Cu" signal "IN4")
		(26 "In12.Cu" signal "GND5")
		(28 "In13.Cu" signal "IN5")
		(30 "In14.Cu" signal "GND6")
		(32 "In15.Cu" signal "IN6")
		(34 "In16.Cu" signal "GND7")
		(2 "B.Cu" signal "BOTTOM")
		(9 "F.Adhes" user "F.Adhesive")
		(11 "B.Adhes" user "B.Adhesive")
		(13 "F.Paste" user "Package Geometry/Pastemask Top")
		(15 "B.Paste" user "Package Geometry/Pastemask Bottom")
		(5 "F.SilkS" user "Ref Des/Silkscreen Top")
		(7 "B.SilkS" user "Ref Des/Silkscreen Bottom")
		(1 "F.Mask" user "Board Geometry/Soldermask Top")
		(3 "B.Mask" user "Board Geometry/Soldermask Bottom")
		(17 "Dwgs.User" user "User.Drawings")
		(19 "Cmts.User" user "User.Comments")
		(21 "Eco1.User" user "User.Eco1")
		(23 "Eco2.User" user "User.Eco2")
		(25 "Edge.Cuts" user "Board Geometry/Outline")
		(27 "Margin" user)
		(31 "F.CrtYd" user "Package Geometry/Place Bound Top")
		(29 "B.CrtYd" user "Package Geometry/Place Bound Bottom")
		(35 "F.Fab" user "Ref Des/Assembly Top")
		(33 "B.Fab" user "Ref Des/Assembly Bottom")
	)
	(footprint ""
		(layer "F.Cu")
		(at 183.679084 -355.898958 90)
		(property "Reference" "PR330"
			(at 0 0 90)
			(layer "F.SilkS")
			(hide yes)
			(effects
				(font
					(size 1.27 1.27)
				)
			)
		)
		(property "Value" ""
			(at 0 0 90)
			(layer "F.Fab")
			(effects
				(font
					(size 1.27 1.27)
				)
			)
		)
		(duplicate_pad_numbers_are_jumpers no)
		(fp_line
			(start 0.7874 -0.4064)
			(end 0.7874 0.4064)
			(stroke
				(width 0.1524)
				(type default)
			)
			(layer "F.SilkS")
		)
		(fp_line
			(start -0.7874 -0.4064)
			(end 0.7874 -0.4064)
			(stroke
				(width 0.1524)
				(type default)
			)
			(layer "F.SilkS")
		)
		(fp_line
			(start 0.7874 0.4064)
			(end -0.7874 0.4064)
			(stroke
				(width 0.1524)
				(type default)
			)
			(layer "F.SilkS")
		)
		(fp_line
			(start -0.7874 0.4064)
			(end -0.7874 -0.4064)
			(stroke
				(width 0.1524)
				(type default)
			)
			(layer "F.SilkS")
		)
		(fp_line
			(start -0.12065 -0.305054)
			(end -0.12065 -0.2794)
			(stroke
				(width 0.1)
				(type default)
			)
			(layer "F.Fab")
		)
		(fp_line
			(start -0.67945 -0.305054)
			(end -0.12065 -0.305054)
			(stroke
				(width 0.1)
				(type default)
			)
			(layer "F.Fab")
		)
		(fp_line
			(start 0.67945 -0.3048)
			(end 0.67945 0.3048)
			(stroke
				(width 0.1)
				(type default)
			)
			(layer "F.Fab")
		)
		(fp_line
			(start 0.12065 -0.3048)
			(end 0.67945 -0.3048)
			(stroke
				(width 0.1)
				(type default)
			)
			(layer "F.Fab")
		)
		(fp_line
			(start 0.12065 -0.2794)
			(end 0.12065 -0.3048)
			(stroke
				(width 0.1)
				(type default)
			)
			(layer "F.Fab")
		)
		(fp_line
			(start -0.12065 -0.2794)
			(end 0.12065 -0.2794)
			(stroke
				(width 0.1)
				(type default)
			)
			(layer "F.Fab")
		)
		(fp_line
			(start 0.120396 0.2794)
			(end -0.12065 0.2794)
			(stroke
				(width 0.1)
				(type default)
			)
			(layer "F.Fab")
		)
		(fp_line
			(start -0.12065 0.2794)
			(end -0.12065 0.3048)
			(stroke
				(width 0.1)
				(type default)
			)
			(layer "F.Fab")
		)
		(fp_line
			(start 0.67945 0.3048)
			(end 0.120396 0.3048)
			(stroke
				(width 0.1)
				(type default)
			)
			(layer "F.Fab")
		)
		(fp_line
			(start 0.120396 0.3048)
			(end 0.120396 0.2794)
			(stroke
				(width 0.1)
				(type default)
			)
			(layer "F.Fab")
		)
		(fp_line
			(start -0.12065 0.3048)
			(end -0.67945 0.3048)
			(stroke
				(width 0.1)
				(type default)
			)
			(layer "F.Fab")
		)
		(fp_line
			(start -0.67945 0.3048)
			(end -0.67945 -0.305054)
			(stroke
				(width 0.1)
				(type default)
			)
			(layer "F.Fab")
		)
		(pad "1" smd circle
			(at -0.40005 0 90)
			(size 0 0)
			(layers "F.Cu" "F.Mask" "F.Paste")
			(net "SW_PVDD11_S3_P1_BOOT1")
		)
		(pad "2" smd circle
			(at 0.40005 0 90)
			(size 0 0)
			(layers "F.Cu" "F.Mask" "F.Paste")
			(net "SW_PVDD11_S3_P1_BOOT1_RC")
		)
	)
	(footprint ""
		(layer "F.Cu")
		(at 18.865088 -373.44985 -90)
		(property "Reference" "PC6630"
			(at 4.41452 2.228088 0)
			(unlocked yes)
			(layer "F.SilkS")
			(effects
				(font
					(size 0.7874 0.5842)
					(thickness 0.1524)
				)
				(justify left)
			)
		)
		(property "Value" ""
			(at 0 0 270)
			(layer "F.Fab")
			(effects
				(font
					(size 1.27 1.27)
				)
			)
		)
		(duplicate_pad_numbers_are_jumpers no)
		(fp_line
			(start -1.988058 2.750058)
			(end 2.750058 2.750058)
			(stroke
				(width 0.1524)
				(type default)
			)
			(layer "F.SilkS")
		)
		(fp_line
			(start 2.750058 2.750058)
			(end 2.750058 0.9398)
			(stroke
				(width 0.1524)
				(type default)
			)
			(layer "F.SilkS")
		)
		(fp_line
			(start -2.750058 1.988058)
			(end -1.988058 2.750058)
			(stroke
				(width 0.1524)
				(type default)
			)
			(layer "F.SilkS")
		)
		(fp_line
			(start -2.750058 0.9398)
			(end -2.750058 1.988058)
			(stroke
				(width 0.1524)
				(type default)
			)
			(layer "F.SilkS")
		)
		(fp_line
			(start 2.750058 -0.9398)
			(end 2.750058 -2.750058)
			(stroke
				(width 0.1524)
				(type default)
			)
			(layer "F.SilkS")
		)
		(fp_line
			(start -2.750058 -1.988058)
			(end -2.750058 -0.9398)
			(stroke
				(width 0.1524)
				(type default)
			)
			(layer "F.SilkS")
		)
		(fp_line
			(start -1.988058 -2.750058)
			(end -2.750058 -1.988058)
			(stroke
				(width 0.1524)
				(type default)
			)
			(layer "F.SilkS")
		)
		(fp_line
			(start 2.750058 -2.750058)
			(end -1.988058 -2.750058)
			(stroke
				(width 0.1524)
				(type default)
			)
			(layer "F.SilkS")
		)
		(fp_line
			(start -2.750058 2.750058)
			(end 2.750058 2.750058)
			(stroke
				(width 0.1)
				(type default)
			)
			(layer "F.Fab")
		)
		(fp_line
			(start 2.750058 2.750058)
			(end 2.750058 -2.750058)
			(stroke
				(width 0.1)
				(type default)
			)
			(layer "F.Fab")
		)
		(fp_line
			(start -2.750058 -2.750058)
			(end -2.750058 2.750058)
			(stroke
				(width 0.1)
				(type default)
			)
			(layer "F.Fab")
		)
		(fp_line
			(start 2.750058 -2.750058)
			(end -2.750058 -2.750058)
			(stroke
				(width 0.1)
				(type default)
			)
			(layer "F.Fab")
		)
		(pad "1" smd rect
			(at -2.199894 0)
			(size 1.6002 3.0226)
			(layers "F.Cu" "F.Mask" "F.Paste")
			(net "P0V9_CPU1_RT_2D")
		)
		(pad "2" smd rect
			(at 2.199894 0)
			(size 1.6002 3.0226)
			(layers "F.Cu" "F.Mask" "F.Paste")
			(net "GND")
		)
	)
)
